G04 ================== begin FILE IDENTIFICATION RECORD ==================*
G04 Layout Name:  15750-1.brd*
G04 Film Name:    L2GND*
G04 File Format:  Gerber RS274X*
G04 File Origin:  Cadence Allegro 16.5-S056*
G04 Origin Date:  Fri Dec 30 13:21:36 2016*
G04 *
G04 Layer:  VIA CLASS/L2GND*
G04 Layer:  PIN/L2GND*
G04 Layer:  ETCH/L2GND*
G04 Layer:  DRAWING FORMAT/LAYER_PCB_STORY*
G04 Layer:  DRAWING FORMAT/LAYER_L2GND*
G04 *
G04 Offset:    (0.00 0.00)*
G04 Mirror:    No*
G04 Mode:      Negative*
G04 Rotation:  0*
G04 FullContactRelief:  No*
G04 UndefLineWidth:     6.00*
G04 ================== end FILE IDENTIFICATION RECORD ====================*
%FSLAX35Y35*MOIN*%
%IR0*IPPOS*OFA0.00000B0.00000*MIA0B0*SFA1.00000B1.00000*%
%ADD15C,.03*%
%ADD14C,.032*%
%ADD17C,.072*%
%ADD16C,.091*%
%ADD20C,.093*%
%ADD18C,.068*%
%AMMACRO12*
4,1,15,.00398,.00044,
.003999,.000208,
.004004,-.000025,
.003996,-.000258,
.00398,-.00044,
.00483,-.00129,
.004897,-.001007,
.004947,-.000721,
.004981,-.000432,
.004997,-.000141,
.004997,.000149,
.00498,.00044,
.004946,.000729,
.004895,.001015,
.00483,.00129,
.00398,.00044,
0.0*
4,1,15,.00044,-.00398,
.000208,-.003999,
-.000025,-.004004,
-.000258,-.003996,
-.00044,-.00398,
-.00129,-.00483,
-.001007,-.004897,
-.000721,-.004947,
-.000432,-.004981,
-.000141,-.004997,
.000149,-.004997,
.00044,-.00498,
.000729,-.004946,
.001015,-.004895,
.00129,-.00483,
.00044,-.00398,
0.0*
4,1,15,-.00398,-.00044,
-.003999,-.000208,
-.004004,.000025,
-.003996,.000258,
-.00398,.00044,
-.00483,.00129,
-.004897,.001007,
-.004947,.000721,
-.004981,.000432,
-.004997,.000141,
-.004997,-.000149,
-.00498,-.00044,
-.004946,-.000729,
-.004895,-.001015,
-.00483,-.00129,
-.00398,-.00044,
0.0*
4,1,15,-.00044,.00398,
-.000208,.003999,
.000025,.004004,
.000258,.003996,
.00044,.00398,
.00129,.00483,
.001007,.004897,
.000721,.004947,
.000432,.004981,
.000141,.004997,
-.000149,.004997,
-.00044,.00498,
-.000729,.004946,
-.001015,.004895,
-.00129,.00483,
-.00044,.00398,
0.0*
%
%ADD12MACRO12*%
%AMMACRO19*
4,1,13,.02632,.01218,
.028035,.007425,
.028899,.002443,
.028884,-.002612,
.027991,-.007588,
.02632,-.01218,
.03005,-.01591,
.032356,-.01045,
.033679,-.004673,
.033979,.001247,
.033246,.007128,
.031504,.012793,
.03005,.01591,
.02632,.01218,
270.*
4,1,13,.01218,-.02632,
.007425,-.028035,
.002443,-.028899,
-.002612,-.028884,
-.007588,-.027991,
-.01218,-.02632,
-.01591,-.03005,
-.01045,-.032356,
-.004673,-.033679,
.001247,-.033979,
.007128,-.033246,
.012793,-.031504,
.01591,-.03005,
.01218,-.02632,
270.*
4,1,13,-.02632,-.01218,
-.028035,-.007425,
-.028899,-.002443,
-.028884,.002612,
-.027991,.007588,
-.02632,.01218,
-.03005,.01591,
-.032356,.01045,
-.033679,.004673,
-.033979,-.001247,
-.033246,-.007128,
-.031504,-.012793,
-.03005,-.01591,
-.02632,-.01218,
270.*
4,1,13,-.01218,.02632,
-.007425,.028035,
-.002443,.028899,
.002612,.028884,
.007588,.027991,
.01218,.02632,
.01591,.03005,
.01045,.032356,
.004673,.033679,
-.001247,.033979,
-.007128,.033246,
-.012793,.031504,
-.01591,.03005,
-.01218,.02632,
270.*
%
%ADD19MACRO19*%
%ADD10C,.114*%
%AMMACRO13*
4,1,15,.00398,.00044,
.003999,.000208,
.004004,-.000025,
.003996,-.000258,
.00398,-.00044,
.00483,-.00129,
.004897,-.001007,
.004947,-.000721,
.004981,-.000432,
.004997,-.000141,
.004997,.000149,
.00498,.00044,
.004946,.000729,
.004895,.001015,
.00483,.00129,
.00398,.00044,
270.*
4,1,15,.00044,-.00398,
.000208,-.003999,
-.000025,-.004004,
-.000258,-.003996,
-.00044,-.00398,
-.00129,-.00483,
-.001007,-.004897,
-.000721,-.004947,
-.000432,-.004981,
-.000141,-.004997,
.000149,-.004997,
.00044,-.00498,
.000729,-.004946,
.001015,-.004895,
.00129,-.00483,
.00044,-.00398,
270.*
4,1,15,-.00398,-.00044,
-.003999,-.000208,
-.004004,.000025,
-.003996,.000258,
-.00398,.00044,
-.00483,.00129,
-.004897,.001007,
-.004947,.000721,
-.004981,.000432,
-.004997,.000141,
-.004997,-.000149,
-.00498,-.00044,
-.004946,-.000729,
-.004895,-.001015,
-.00483,-.00129,
-.00398,-.00044,
270.*
4,1,15,-.00044,.00398,
-.000208,.003999,
.000025,.004004,
.000258,.003996,
.00044,.00398,
.00129,.00483,
.001007,.004897,
.000721,.004947,
.000432,.004981,
.000141,.004997,
-.000149,.004997,
-.00044,.00498,
-.000729,.004946,
-.001015,.004895,
-.00129,.00483,
-.00044,.00398,
270.*
%
%ADD13MACRO13*%
%AMMACRO11*
4,1,16,.07256,.04427,
.079145,.030998,
.083325,.016783,
.084974,.002059,
.08404,-.012728,
.080553,-.027128,
.074619,-.040704,
.07256,-.04427,
.07619,-.04791,
.083352,-.033952,
.087981,-.018962,
.089937,-.003396,
.089161,.012273,
.085675,.027569,
.079586,.042027,
.07619,.04791,
.07256,.04427,
0.0*
4,1,16,.04427,-.07256,
.030998,-.079145,
.016783,-.083325,
.002059,-.084974,
-.012728,-.08404,
-.027128,-.080553,
-.040704,-.074619,
-.04427,-.07256,
-.04791,-.07619,
-.033952,-.083352,
-.018962,-.087981,
-.003396,-.089937,
.012273,-.089161,
.027569,-.085675,
.042027,-.079586,
.04791,-.07619,
.04427,-.07256,
0.0*
4,1,16,-.07256,-.04427,
-.079145,-.030998,
-.083325,-.016783,
-.084974,-.002059,
-.08404,.012728,
-.080553,.027128,
-.074619,.040704,
-.07256,.04427,
-.07619,.04791,
-.083352,.033952,
-.087981,.018962,
-.089937,.003396,
-.089161,-.012273,
-.085675,-.027569,
-.079586,-.042027,
-.07619,-.04791,
-.07256,-.04427,
0.0*
4,1,16,-.04427,.07256,
-.030998,.079145,
-.016783,.083325,
-.002059,.084974,
.012728,.08404,
.027128,.080553,
.040704,.074619,
.04427,.07256,
.04791,.07619,
.033952,.083352,
.018962,.087981,
.003396,.089937,
-.012273,.089161,
-.027569,.085675,
-.042027,.079586,
-.04791,.07619,
-.04427,.07256,
0.0*
%
%ADD11MACRO11*%
%ADD21C,.02*%
%ADD22C,.006*%
%ADD25C,.06804*%
%ADD24C,.08704*%
%ADD28C,.08904*%
%ADD27R,.06102X.0471*%
%ADD26R,.06102X.04708*%
%ADD23O,.04824X.09264*%
G75*
%LPD*%
G75*
G36*
G01X-6000Y-6000D02*
X355409D01*
Y369425D01*
X-6000D01*
Y-6000D01*
G37*
%LPC*%
G75*
G36*
G01X223819Y1904D02*
G02X217849Y7874I0J5970D01*
G01Y258071D01*
G03X208071Y267849I-9778J0D01*
G01X7874D01*
G02X1904Y273819I0J5970D01*
G01Y355551D01*
G02X7874Y361521I5970J0D01*
G01X341535D01*
G02X347505Y355551I0J-5970D01*
G01Y278779D01*
G02X347441Y278715I-64J0D01*
G01X339566D01*
G03X335694Y274843I1J-3873D01*
G01Y219567D01*
G03X339567Y215694I3873J0D01*
G01X347441D01*
G02X347505Y215630I0J-64D01*
G01Y195925D01*
G02X347441Y195861I-64J0D01*
G01X321062D01*
G03X317190Y191989I1J-3873D01*
G01Y175256D01*
G03X321063Y171383I3873J0D01*
G01X323938D01*
G02X324212Y170691I0J-400D01*
G03X323732Y169587I1032J-1105D01*
G01Y166437D01*
G03X325720Y165002I1512J0D01*
G02X326246Y164623I126J-379D01*
G01Y161952D01*
G02X325720Y161573I-400J0D01*
G03X323732Y160138I-476J-1435D01*
G01Y156988D01*
G03X325720Y155553I1512J0D01*
G02X326246Y155174I126J-379D01*
G01Y152502D01*
G02X325720Y152122I-400J0D01*
G03X323734Y150689I-476J-1433D01*
G01Y147540D01*
G03X325720Y146107I1510J0D01*
G02X326246Y145727I126J-380D01*
G01Y111558D01*
G02X325720Y111179I-400J0D01*
G03X323732Y109744I-476J-1435D01*
G01Y106595D01*
G03X325720Y105160I1512J0D01*
G02X326246Y104781I126J-379D01*
G01Y102110D01*
G02X325720Y101731I-400J0D01*
G03X323732Y100296I-476J-1435D01*
G01Y97146D01*
G03X325720Y95711I1512J0D01*
G02X326246Y95332I126J-379D01*
G01Y92661D01*
G02X325720Y92282I-400J0D01*
G03X323732Y90847I-476J-1435D01*
G01Y87697D01*
G03X325720Y86262I1512J0D01*
G02X326246Y85883I126J-379D01*
G01Y83212D01*
G02X325720Y82833I-400J0D01*
G03X323732Y81399I-476J-1435D01*
G01Y78248D01*
G03X325720Y76813I1512J0D01*
G02X326246Y76434I126J-379D01*
G01Y73763D01*
G02X325720Y73384I-400J0D01*
G03X323732Y71949I-476J-1435D01*
G01Y68799D01*
G03X325720Y67364I1512J0D01*
G02X326246Y66985I126J-379D01*
G01Y64314D01*
G02X325720Y63935I-400J0D01*
G03X323732Y62501I-476J-1435D01*
G01Y59351D01*
G03X325720Y57916I1512J0D01*
G02X326246Y57537I126J-379D01*
G01Y46004D01*
G02X326181Y45939I-65J0D01*
G01X321062D01*
G03X317190Y42067I1J-3873D01*
G01Y25334D01*
G03X321062Y21462I3873J1D01*
G01X347441D01*
G02X347505Y21398I0J-64D01*
G01Y1968D01*
G02X347441Y1904I-64J0D01*
G01X223819D01*
G37*
%LPD*%
G75*
G36*
G01X300388Y137043D02*
G02X305212I2412J0D01*
G01Y132642D01*
G02X300388Y132643I-2412J1D01*
G01Y137043D01*
G37*
G36*
G01X292988Y89899D02*
G02X297012I2012J0D01*
G01Y86698D01*
G02X292988Y86699I-2012J1D01*
G01Y89899D01*
G37*
G36*
G01X277512Y222811D02*
Y218371D01*
G02X272688Y218372I-2412J1D01*
G01Y222812D01*
G02X277512Y222811I2412J-1D01*
G37*
G36*
G01X275512Y211000D02*
Y206560D01*
G02X270688Y206561I-2412J1D01*
G01Y211001D01*
G02X275512Y211000I2412J-1D01*
G37*
G36*
G01X293312Y198561D02*
Y195360D01*
G02X289466Y194536I-2012J1D01*
G01X289413Y194654D01*
X283268D01*
Y199362D01*
X289455D01*
G02X293312Y198561I1845J-801D01*
G37*
G36*
G01X275512Y102339D02*
Y97898D01*
G02X270688Y97899I-2412J1D01*
G01Y102339D01*
G02X275512I2412J0D01*
G37*
G54D25*
X265551Y143464D03*
Y252126D03*
G54D24*
Y64724D03*
Y173386D03*
X311614Y31870D03*
G54D28*
Y185414D03*
G54D27*
X286319Y100197D03*
Y208819D03*
G54D26*
Y94292D03*
Y88346D03*
Y112008D03*
Y106102D03*
Y202914D03*
Y220630D03*
Y214724D03*
G54D23*
X275100Y111930D03*
G54D15*
X95000Y277500D03*
X99000D03*
X106500D03*
X92500Y295000D03*
X106137Y286000D03*
X100000Y288500D03*
X92500Y298500D03*
Y309000D03*
X107000Y311500D03*
Y308000D03*
X100250Y313200D03*
X103500Y317000D03*
Y321000D03*
X91500Y312500D03*
X96750Y328500D03*
X100500Y347289D03*
X121500Y276500D03*
X118000D03*
X114500D03*
X110500Y277500D03*
X121456Y289154D03*
X112500Y289000D03*
X108000Y295000D03*
Y298500D03*
X115000Y305000D03*
X119000D03*
X108000Y303100D03*
X120120Y315000D03*
X116500D03*
X109500Y334500D03*
X113000D03*
X117000D03*
X121000D03*
X125000Y277000D03*
X128500Y282500D03*
X126000Y287000D03*
X130000Y298500D03*
X215064Y316100D03*
X237000Y156000D03*
Y159780D03*
Y152500D03*
X236500Y168500D03*
X225000Y169500D03*
X237000Y164250D03*
X251000Y88500D03*
X252000Y151500D03*
Y155000D03*
Y160500D03*
X251000Y197000D03*
X263000Y96500D03*
Y88500D03*
Y81338D03*
Y84838D03*
Y104000D03*
X262819Y100157D03*
X268140Y161221D03*
X258750Y168000D03*
X263000Y190000D03*
Y193500D03*
Y205000D03*
Y197000D03*
Y212500D03*
X262819Y208819D03*
X263000Y240315D03*
X275100Y109710D03*
X273100Y102299D03*
Y97899D03*
X275100Y114110D03*
X279000Y166000D03*
X273100Y210961D03*
Y206561D03*
X275100Y222772D03*
Y218372D03*
X295000Y86699D03*
Y89899D03*
X301000Y125000D03*
X292000Y126000D03*
X302800Y137043D03*
Y132643D03*
X290500Y154250D03*
X296500Y157500D03*
X290500Y150750D03*
X291000Y169500D03*
X291300Y195361D03*
Y198561D03*
X325244Y49902D03*
Y53051D03*
Y62500D03*
Y59351D03*
Y78248D03*
Y68799D03*
Y71949D03*
Y97146D03*
Y87697D03*
Y90847D03*
Y81398D03*
Y106595D03*
Y109744D03*
Y100296D03*
Y156988D03*
Y160138D03*
Y150689D03*
Y147540D03*
Y166437D03*
Y169587D03*
G54D14*
X72000Y286000D03*
Y290000D03*
X58000Y310689D03*
X79000Y344000D03*
Y348000D03*
X138500Y299500D03*
X134500Y307500D03*
X138500Y303500D03*
Y307500D03*
X137500Y324500D03*
X142500Y299500D03*
Y303500D03*
Y307500D03*
X141811Y324500D03*
X145811D03*
X153811D03*
X149811D03*
X162311Y293000D03*
X160811Y310000D03*
X169811Y309500D03*
X172311Y305500D03*
X157811Y324500D03*
X161811D03*
X169811D03*
X165811D03*
X169811Y313500D03*
X176311Y294000D03*
X181061Y297750D03*
X176168Y305500D03*
X195811Y296000D03*
X200811Y308000D03*
Y311000D03*
Y317000D03*
Y314000D03*
X218000Y292000D03*
X215811Y300000D03*
X222311Y325000D03*
X218311D03*
X230000Y96500D03*
X225000Y205000D03*
X222911Y287089D03*
X247000Y68838D03*
Y72838D03*
X251000Y68838D03*
Y72838D03*
X247000Y123838D03*
X251000D03*
X247000Y127838D03*
X251000D03*
X247000Y136338D03*
Y140838D03*
X251000D03*
Y136338D03*
Y177500D03*
X247000D03*
X251000Y181500D03*
X247000D03*
X251000Y245000D03*
X247000D03*
X251000Y236500D03*
X247000D03*
X251000Y232500D03*
X247000D03*
X251000Y249500D03*
X247000D03*
X242500Y294000D03*
X246500D03*
X250500D03*
X242500Y306000D03*
Y302000D03*
Y298000D03*
X246500Y306000D03*
Y302000D03*
Y298000D03*
X250500D03*
Y302000D03*
Y306000D03*
X262920Y131653D03*
X273000Y92283D03*
X299500Y46000D03*
X303500D03*
X296500Y61000D03*
X300500D03*
X301500Y49000D03*
X297500D03*
X295500Y52000D03*
X299500D03*
X295500Y110000D03*
X295311Y127600D03*
X304500Y123820D03*
X301711Y245000D03*
G54D17*
X265551Y143464D03*
Y252126D03*
G54D16*
Y64724D03*
Y173386D03*
X311614Y31870D03*
G54D20*
Y185414D03*
G54D18*
X302000Y290500D03*
Y300500D03*
G54D12*
X10000Y330000D03*
Y345000D03*
Y360000D03*
X40000Y270000D03*
Y285000D03*
Y300000D03*
Y330000D03*
Y345000D03*
X25000Y360000D03*
X40000D03*
X55000Y270000D03*
Y285000D03*
Y360000D03*
X70000Y270000D03*
Y360000D03*
X85000Y270000D03*
Y360000D03*
X100000Y270000D03*
X103000Y277500D03*
X96750Y313250D03*
X103750Y313200D03*
X100500Y335689D03*
X100000Y360000D03*
X122100Y280750D03*
X122000Y301000D03*
X115000Y360000D03*
X124000Y315000D03*
X138000Y341500D03*
X130000Y360000D03*
X138000Y345500D03*
X140500Y281000D03*
X146500Y303500D03*
X150500D03*
X146500Y307500D03*
X150500D03*
X155000Y301350D03*
X149811Y341500D03*
X141811D03*
X145811D03*
X153811D03*
X145000Y360000D03*
X149811Y345500D03*
X141811D03*
X145811D03*
X153811D03*
X164811Y304000D03*
X165811Y341500D03*
X157811D03*
X161811D03*
X169811D03*
X160000Y360000D03*
X165811Y345500D03*
X169811D03*
X157811D03*
X161811D03*
X185811Y304200D03*
Y310500D03*
X181811D03*
Y318500D03*
X185811Y314500D03*
Y326500D03*
Y322500D03*
Y318500D03*
X181811Y326500D03*
Y322500D03*
Y314500D03*
X184500Y334000D03*
Y338000D03*
X175000Y360000D03*
X189811Y310500D03*
Y318500D03*
Y322500D03*
Y326500D03*
Y314500D03*
X190000Y360000D03*
X205000D03*
X220000D03*
X225000Y35000D03*
Y50000D03*
Y80000D03*
Y65000D03*
X230000Y75000D03*
Y67000D03*
Y71000D03*
X225000Y95000D03*
Y110000D03*
X230000Y126000D03*
Y130000D03*
Y122000D03*
Y138500D03*
Y142500D03*
Y134500D03*
X236805Y146452D03*
X225000Y160250D03*
Y149250D03*
Y164250D03*
X230000Y175500D03*
Y179500D03*
Y183500D03*
Y243000D03*
Y234500D03*
Y238500D03*
Y230500D03*
Y247000D03*
Y251000D03*
X237500Y340000D03*
Y344000D03*
Y336000D03*
X235000Y360000D03*
X255000Y5000D03*
Y35000D03*
X251500Y164500D03*
X249000Y260000D03*
X241500Y336000D03*
Y344000D03*
Y340000D03*
X250000Y360000D03*
X270000Y5000D03*
Y35000D03*
X269650Y97899D03*
X271650Y109710D03*
X269650Y102299D03*
X271650Y114110D03*
X271250Y138750D03*
X267700Y153250D03*
X269650Y210961D03*
Y206561D03*
X271650Y222772D03*
Y218372D03*
X265000Y270000D03*
Y285000D03*
X271500Y294000D03*
X267500D03*
X271500Y306000D03*
Y302000D03*
Y298000D03*
X267500D03*
Y302000D03*
Y306000D03*
X260500Y340000D03*
Y344000D03*
Y336000D03*
X256500D03*
Y344000D03*
Y340000D03*
X265000Y360000D03*
X282500Y5000D03*
X272500Y20000D03*
X285000Y32500D03*
X275500Y63346D03*
X280000Y71614D03*
Y67677D03*
X280169Y126732D03*
Y120826D03*
X275768Y144842D03*
X280169Y138543D03*
Y132637D03*
X278860Y162250D03*
X280000Y176339D03*
X275500Y172008D03*
X280000Y180276D03*
X273500Y194055D03*
Y199961D03*
X273600Y240250D03*
X280169Y247205D03*
X275768Y253504D03*
X280000Y270000D03*
X275500Y294000D03*
X280000Y285000D03*
X275500Y298000D03*
Y302000D03*
Y306000D03*
X280000Y300000D03*
Y315000D03*
X295000Y5000D03*
X300000Y20000D03*
Y35000D03*
X304565Y61142D03*
Y96142D03*
X304500Y92000D03*
X291500Y97204D03*
X291550Y91299D03*
X291500Y85393D03*
X295500Y100000D03*
X291500Y109960D03*
Y101960D03*
Y114921D03*
X300500Y129100D03*
X299300Y137043D03*
X304565Y141142D03*
X299300Y132643D03*
X302000Y157500D03*
X292000Y181500D03*
X294750Y195261D03*
X295500Y208461D03*
X294750Y198661D03*
X291500Y210961D03*
Y205866D03*
Y218461D03*
Y223583D03*
Y241299D03*
Y229488D03*
Y235394D03*
X295000Y270000D03*
Y285000D03*
Y300000D03*
Y315000D03*
X315000Y5000D03*
Y20000D03*
Y40000D03*
X313000Y179500D03*
X310000Y225000D03*
Y240000D03*
Y255000D03*
Y270000D03*
Y285000D03*
Y300000D03*
Y315000D03*
Y330000D03*
Y360000D03*
Y345000D03*
X325244Y56201D03*
Y75099D03*
Y65650D03*
Y93996D03*
Y84548D03*
Y112894D03*
Y103445D03*
Y128642D03*
Y119193D03*
Y144390D03*
Y138091D03*
Y153839D03*
Y163288D03*
X324302Y203977D03*
X325000Y225000D03*
Y240000D03*
Y255000D03*
Y270000D03*
Y285000D03*
Y300000D03*
Y315000D03*
Y330000D03*
Y360000D03*
Y345000D03*
X345000Y5000D03*
Y20000D03*
X340000Y285000D03*
Y300000D03*
Y315000D03*
Y330000D03*
Y360000D03*
Y345000D03*
G54D19*
X302000Y310500D03*
G54D10*
X26087Y-114844D03*
X26435Y373984D03*
X175335Y62719D03*
Y189062D03*
X547104Y69007D03*
Y195351D03*
X696192Y373984D03*
G54D13*
X52500Y325189D03*
Y331189D03*
X59500Y294189D03*
X64500Y309589D03*
X59500Y299939D03*
X71500Y315689D03*
X67900D03*
X72000Y336689D03*
X89000Y295189D03*
Y291189D03*
Y287189D03*
Y283189D03*
Y303689D03*
Y299689D03*
X75100Y315689D03*
X89000Y329189D03*
Y333189D03*
G54D11*
X25596Y316176D03*
X237013Y17712D03*
X287407Y345704D03*
%LPC*%
G75*
G54D21*
G01X-176139Y-183003D02*
G02I-12000J0D01*
G01X-181289D02*
G02I-6850J0D01*
G01X-172139D02*
X-204139D01*
G01X-188139Y-199003D02*
Y-167003D01*
G01X-172139Y-199003D02*
Y-279003D01*
G01D02*
X1178561D01*
G01X-172139Y-234503D02*
X1178561D01*
G01X-172139Y-199003D02*
X1178561D01*
G01X391061D02*
Y-279003D01*
G01X528561Y-199003D02*
Y-279003D01*
G01X643561Y-199003D02*
Y-279003D01*
G01X811061Y-199003D02*
Y-279003D01*
G01X981061Y-199003D02*
Y-279003D01*
G01X1178561Y-199003D02*
Y-279003D01*
G01X1210561Y-183003D02*
X1178561D01*
G01X1206561D02*
G02I-12000J0D01*
G01X1201411D02*
G02I-6850J0D01*
G01X1194561Y-199003D02*
Y-167003D01*
G54D22*
G01X-148956Y-251503D02*
Y-269003D01*
X-140222D01*
G01X-127089Y-257337D02*
Y-269003D01*
G01Y-252670D02*
X-127526Y-252378D01*
Y-251795D01*
X-127089Y-251503D01*
X-126652Y-251795D01*
Y-252378D01*
X-127089Y-252670D01*
G01X-112646Y-273378D02*
X-111117Y-274545D01*
X-109371Y-274836D01*
X-107843Y-274545D01*
X-106532Y-273087D01*
X-105659Y-271045D01*
Y-257337D01*
G01Y-259670D02*
X-106532Y-258503D01*
X-107843Y-257628D01*
X-109371Y-257337D01*
X-111117Y-257920D01*
X-112209Y-259086D01*
X-113083Y-261128D01*
X-113519Y-263170D01*
X-113301Y-264920D01*
X-112427Y-266962D01*
X-111117Y-268420D01*
X-109371Y-269003D01*
X-108061Y-268711D01*
X-106532Y-267545D01*
X-105659Y-266379D01*
G01X-95801Y-269003D02*
Y-251503D01*
G01Y-259961D02*
X-94709Y-258503D01*
X-93617Y-257628D01*
X-91871Y-257337D01*
X-90561Y-257628D01*
X-89032Y-258795D01*
X-88377Y-260545D01*
Y-269003D01*
G01X-74589Y-251503D02*
Y-269003D01*
G01X-77646Y-257337D02*
X-71532D01*
G01X-60801Y-269003D02*
Y-257337D01*
G01Y-260253D02*
X-59927Y-258795D01*
X-58617Y-257628D01*
X-56871Y-257337D01*
X-55343Y-257628D01*
X-54032Y-258795D01*
X-53377Y-260836D01*
Y-269003D01*
G01X-39589Y-257337D02*
Y-269003D01*
G01Y-252670D02*
X-40026Y-252378D01*
Y-251795D01*
X-39589Y-251503D01*
X-39152Y-251795D01*
Y-252378D01*
X-39589Y-252670D01*
G01X-25801Y-269003D02*
Y-257337D01*
G01Y-260253D02*
X-24927Y-258795D01*
X-23617Y-257628D01*
X-21871Y-257337D01*
X-20343Y-257628D01*
X-19032Y-258795D01*
X-18377Y-260836D01*
Y-269003D01*
G01X-7646Y-273378D02*
X-6117Y-274545D01*
X-4371Y-274836D01*
X-2843Y-274545D01*
X-1532Y-273087D01*
X-659Y-271045D01*
Y-257337D01*
G01Y-259670D02*
X-1532Y-258503D01*
X-2843Y-257628D01*
X-4371Y-257337D01*
X-6117Y-257920D01*
X-7209Y-259086D01*
X-8083Y-261128D01*
X-8519Y-263170D01*
X-8301Y-264920D01*
X-7427Y-266962D01*
X-6117Y-268420D01*
X-4371Y-269003D01*
X-3061Y-268711D01*
X-1532Y-267545D01*
X-659Y-266379D01*
G01X26044Y-269003D02*
Y-251503D01*
X31284D01*
X33031Y-252378D01*
X34341Y-254420D01*
X34778Y-256753D01*
X34341Y-259086D01*
X33249Y-260836D01*
X31284Y-261712D01*
X26044D01*
G01X42452Y-251503D02*
X47911Y-269003D01*
X53370Y-251503D01*
G01X65411D02*
Y-269003D01*
G01X60389Y-251503D02*
X70433D01*
G01X94734Y-269003D02*
Y-251503D01*
X100411Y-266086D01*
X106088Y-251503D01*
Y-269003D01*
G01X117911Y-269586D02*
X117474Y-269295D01*
Y-268711D01*
X117911Y-268420D01*
X118348Y-268711D01*
Y-269295D01*
X117911Y-269586D01*
G01X131263Y-254420D02*
X132573Y-252670D01*
X134101Y-251795D01*
X135848Y-251503D01*
X138031Y-252086D01*
X139559Y-253545D01*
X139996Y-255294D01*
X139778Y-257045D01*
X138904Y-258503D01*
X134538Y-261420D01*
X132573Y-263461D01*
X131263Y-266379D01*
X130826Y-269003D01*
X139996D01*
G01X164952D02*
X170411Y-251503D01*
X175870Y-269003D01*
G01X173904Y-262878D02*
X166917D01*
G01X191841Y-251503D02*
Y-269003D01*
G01Y-266379D02*
X190968Y-267837D01*
X189657Y-268711D01*
X188129Y-269003D01*
X186383Y-268420D01*
X185073Y-266962D01*
X184199Y-265212D01*
X183981Y-263170D01*
X184199Y-261128D01*
X185073Y-259378D01*
X186383Y-257920D01*
X188129Y-257337D01*
X189657Y-257628D01*
X190749Y-258212D01*
X191841Y-259378D01*
G01X209341Y-269003D02*
Y-257337D01*
G01Y-259378D02*
X208468Y-258212D01*
X207157Y-257628D01*
X205629Y-257337D01*
X204101Y-257920D01*
X202791Y-259086D01*
X201917Y-260836D01*
X201481Y-263170D01*
X201917Y-265503D01*
X202791Y-267253D01*
X204101Y-268420D01*
X205629Y-269003D01*
X207157Y-268711D01*
X208468Y-267837D01*
X209341Y-266670D01*
G01X218981Y-274836D02*
Y-257337D01*
G01Y-259961D02*
X220073Y-258503D01*
X221164Y-257628D01*
X222911Y-257337D01*
X224439Y-257628D01*
X225968Y-259086D01*
X226623Y-261128D01*
X226841Y-263170D01*
X226623Y-265212D01*
X225968Y-267253D01*
X224657Y-268420D01*
X222911Y-269003D01*
X221383Y-268711D01*
X219854Y-267837D01*
X218981Y-266670D01*
G01X240411Y-251503D02*
Y-269003D01*
G01X237354Y-257337D02*
X243468D01*
G01X257911Y-269003D02*
X256601Y-268711D01*
X255291Y-267545D01*
X254417Y-265503D01*
X253981Y-263170D01*
X254417Y-260836D01*
X255291Y-258795D01*
X256601Y-257628D01*
X257911Y-257337D01*
X259221Y-257628D01*
X260531Y-258795D01*
X261404Y-260836D01*
X261623Y-263170D01*
X261404Y-265503D01*
X260531Y-267545D01*
X259221Y-268711D01*
X257911Y-269003D01*
G01X272354D02*
Y-257337D01*
G01Y-259670D02*
X273446Y-258503D01*
X274538Y-257628D01*
X276066Y-257337D01*
X277157Y-257628D01*
X278468Y-258503D01*
G01X315214Y-252962D02*
X313904Y-252086D01*
X312376Y-251503D01*
X310629D01*
X308664Y-252378D01*
X307136Y-253836D01*
X306044Y-255587D01*
X305171Y-258503D01*
X304952Y-261128D01*
X305389Y-263753D01*
X306044Y-265503D01*
X307354Y-267253D01*
X308883Y-268420D01*
X310411Y-269003D01*
X311939D01*
X313468Y-268420D01*
X314778Y-267545D01*
X315870Y-266379D01*
G01X331841Y-269003D02*
Y-257337D01*
G01Y-259378D02*
X330968Y-258212D01*
X329657Y-257628D01*
X328129Y-257337D01*
X326601Y-257920D01*
X325291Y-259086D01*
X324417Y-260836D01*
X323981Y-263170D01*
X324417Y-265503D01*
X325291Y-267253D01*
X326601Y-268420D01*
X328129Y-269003D01*
X329657Y-268711D01*
X330968Y-267837D01*
X331841Y-266670D01*
G01X342354Y-269003D02*
Y-257337D01*
G01Y-259670D02*
X343446Y-258503D01*
X344538Y-257628D01*
X346066Y-257337D01*
X347157Y-257628D01*
X348468Y-258503D01*
G01X366841Y-251503D02*
Y-269003D01*
G01Y-266379D02*
X365968Y-267837D01*
X364657Y-268711D01*
X363129Y-269003D01*
X361383Y-268420D01*
X360073Y-266962D01*
X359199Y-265212D01*
X358981Y-263170D01*
X359199Y-261128D01*
X360073Y-259378D01*
X361383Y-257920D01*
X363129Y-257337D01*
X364657Y-257628D01*
X365749Y-258212D01*
X366841Y-259378D01*
G01X68484Y-224003D02*
Y-206503D01*
X74161Y-221086D01*
X79838Y-206503D01*
Y-224003D01*
G01X91661D02*
X90351Y-223711D01*
X89041Y-222545D01*
X88167Y-220503D01*
X87731Y-218170D01*
X88167Y-215836D01*
X89041Y-213795D01*
X90351Y-212628D01*
X91661Y-212337D01*
X92971Y-212628D01*
X94281Y-213795D01*
X95154Y-215836D01*
X95373Y-218170D01*
X95154Y-220503D01*
X94281Y-222545D01*
X92971Y-223711D01*
X91661Y-224003D01*
G01X113091Y-206503D02*
Y-224003D01*
G01Y-221379D02*
X112218Y-222837D01*
X110907Y-223711D01*
X109379Y-224003D01*
X107633Y-223420D01*
X106323Y-221962D01*
X105449Y-220212D01*
X105231Y-218170D01*
X105449Y-216128D01*
X106323Y-214378D01*
X107633Y-212920D01*
X109379Y-212337D01*
X110907Y-212628D01*
X111999Y-213212D01*
X113091Y-214378D01*
G01X123386Y-216128D02*
X130373D01*
X129718Y-214086D01*
X128626Y-212920D01*
X127098Y-212337D01*
X125569Y-212628D01*
X124259Y-213503D01*
X123386Y-215545D01*
X122949Y-217295D01*
Y-219045D01*
X123386Y-220795D01*
X124478Y-222545D01*
X125788Y-223711D01*
X127316Y-224003D01*
X128844Y-223420D01*
X130373Y-221670D01*
G01X144161Y-224003D02*
Y-206503D01*
G01X424761Y-269003D02*
Y-251503D01*
X422141Y-255003D01*
G01Y-269003D02*
X427381D01*
G01X437458Y-266379D02*
X438767Y-267837D01*
X440296Y-268711D01*
X442261Y-269003D01*
X444226Y-268420D01*
X445754Y-267253D01*
X446846Y-265212D01*
X447064Y-262878D01*
X446628Y-260545D01*
X445536Y-259086D01*
X444007Y-257920D01*
X442479Y-257628D01*
X440951Y-257920D01*
X438986Y-259086D01*
X439641Y-251503D01*
X445536D01*
G01X459324Y-269003D02*
X459761Y-265212D01*
X460416Y-262003D01*
X461289Y-259086D01*
X462381Y-255878D01*
X464128Y-251503D01*
X455394D01*
G01X472458Y-266379D02*
X473767Y-267837D01*
X475296Y-268711D01*
X477261Y-269003D01*
X479226Y-268420D01*
X480754Y-267253D01*
X481846Y-265212D01*
X482064Y-262878D01*
X481628Y-260545D01*
X480536Y-259086D01*
X479007Y-257920D01*
X477479Y-257628D01*
X475951Y-257920D01*
X473986Y-259086D01*
X474641Y-251503D01*
X480536D01*
G01X494761D02*
X493014Y-252086D01*
X491704Y-253545D01*
X490831Y-255294D01*
X490176Y-257628D01*
X489958Y-260253D01*
X490176Y-262878D01*
X490831Y-265212D01*
X491704Y-266962D01*
X493014Y-268420D01*
X494761Y-269003D01*
X496507Y-268420D01*
X497818Y-266962D01*
X498691Y-265212D01*
X499346Y-262878D01*
X499564Y-260253D01*
X499346Y-257628D01*
X498691Y-255294D01*
X497818Y-253545D01*
X496507Y-252086D01*
X494761Y-251503D01*
G01X411644Y-224003D02*
Y-206503D01*
X416884D01*
X418631Y-207378D01*
X419941Y-209420D01*
X420378Y-211753D01*
X419941Y-214086D01*
X418849Y-215836D01*
X416884Y-216712D01*
X411644D01*
G01X438314Y-207962D02*
X437004Y-207086D01*
X435476Y-206503D01*
X433729D01*
X431764Y-207378D01*
X430236Y-208836D01*
X429144Y-210587D01*
X428271Y-213503D01*
X428052Y-216128D01*
X428489Y-218753D01*
X429144Y-220503D01*
X430454Y-222253D01*
X431983Y-223420D01*
X433511Y-224003D01*
X435039D01*
X436568Y-223420D01*
X437878Y-222545D01*
X438970Y-221379D01*
G01X452757Y-214670D02*
X453631Y-213795D01*
X454286Y-212337D01*
X454723Y-210294D01*
X454286Y-208545D01*
X453413Y-207378D01*
X451884Y-206503D01*
X445989D01*
Y-224003D01*
X453194D01*
X454723Y-222837D01*
X455596Y-221086D01*
X456033Y-219045D01*
X455596Y-217003D01*
X454286Y-215253D01*
X452757Y-214670D01*
X445989D01*
G01X461961Y-229836D02*
X475061D01*
G01X480989Y-224003D02*
Y-206503D01*
X491033Y-224003D01*
Y-206503D01*
G01X503511Y-224003D02*
X501764Y-223711D01*
X500236Y-222545D01*
X498926Y-220795D01*
X498052Y-218753D01*
X497616Y-216420D01*
Y-214086D01*
X498052Y-211753D01*
X498926Y-209711D01*
X500236Y-207962D01*
X501764Y-206795D01*
X503511Y-206503D01*
X505257Y-206795D01*
X506786Y-207962D01*
X508096Y-209711D01*
X508970Y-211753D01*
X509406Y-214086D01*
Y-216420D01*
X508970Y-218753D01*
X508096Y-220795D01*
X506786Y-222545D01*
X505257Y-223711D01*
X503511Y-224003D01*
G01X554352Y-206503D02*
X559811Y-224003D01*
X565270Y-206503D01*
G01X581678Y-224003D02*
X572944D01*
Y-206503D01*
X581678D01*
G01X578184Y-214961D02*
X572944D01*
G01X590444Y-224003D02*
Y-206503D01*
X595903D01*
X597649Y-207378D01*
X598741Y-208545D01*
X599178Y-210878D01*
X598741Y-213212D01*
X597431Y-214670D01*
X595903Y-215545D01*
X590444D01*
G01X595903D02*
X599178Y-224003D01*
G01X612311Y-224586D02*
X611874Y-224295D01*
Y-223711D01*
X612311Y-223420D01*
X612748Y-223711D01*
Y-224295D01*
X612311Y-224586D01*
G01X586061Y-269003D02*
Y-251503D01*
X583441Y-255003D01*
G01Y-269003D02*
X588681D01*
G01X687894Y-251503D02*
Y-269003D01*
X696628D01*
G01X705613Y-254420D02*
X706923Y-252670D01*
X708451Y-251795D01*
X710198Y-251503D01*
X712381Y-252086D01*
X713909Y-253545D01*
X714346Y-255294D01*
X714128Y-257045D01*
X713254Y-258503D01*
X708888Y-261420D01*
X706923Y-263461D01*
X705613Y-266379D01*
X705176Y-269003D01*
X714346D01*
G01X728571Y-260253D02*
X732938D01*
Y-265503D01*
X731628Y-267253D01*
X730099Y-268420D01*
X727916Y-269003D01*
X725733Y-268420D01*
X724204Y-267253D01*
X722894Y-265503D01*
X722021Y-263461D01*
X721584Y-261128D01*
Y-259086D01*
X722021Y-257337D01*
X722894Y-255294D01*
X724204Y-253545D01*
X725514Y-252378D01*
X727261Y-251503D01*
X728789D01*
X730536Y-252086D01*
X731846Y-253253D01*
G01X739739Y-269003D02*
Y-251503D01*
X749783Y-269003D01*
Y-251503D01*
G01X757458Y-269003D02*
Y-251503D01*
X761824D01*
X763571Y-252378D01*
X764881Y-253545D01*
X765973Y-255294D01*
X766846Y-257337D01*
X767064Y-260253D01*
X766846Y-263170D01*
X765973Y-265212D01*
X764881Y-266962D01*
X763571Y-268128D01*
X761824Y-269003D01*
X757458D01*
G01X687894Y-206503D02*
Y-224003D01*
X696628D01*
G01X713691D02*
Y-212337D01*
G01Y-214378D02*
X712818Y-213212D01*
X711507Y-212628D01*
X709979Y-212337D01*
X708451Y-212920D01*
X707141Y-214086D01*
X706267Y-215836D01*
X705831Y-218170D01*
X706267Y-220503D01*
X707141Y-222253D01*
X708451Y-223420D01*
X709979Y-224003D01*
X711507Y-223711D01*
X712818Y-222837D01*
X713691Y-221670D01*
G01X722676Y-229253D02*
X723986Y-229836D01*
X725733Y-229253D01*
X726824Y-228087D01*
X727698Y-226628D01*
X729007Y-221962D01*
X731846Y-212337D01*
G01X724859D02*
X729007Y-221962D01*
G01X741486Y-216128D02*
X748473D01*
X747818Y-214086D01*
X746726Y-212920D01*
X745198Y-212337D01*
X743669Y-212628D01*
X742359Y-213503D01*
X741486Y-215545D01*
X741049Y-217295D01*
Y-219045D01*
X741486Y-220795D01*
X742578Y-222545D01*
X743888Y-223711D01*
X745416Y-224003D01*
X746944Y-223420D01*
X748473Y-221670D01*
G01X759204Y-224003D02*
Y-212337D01*
G01Y-214670D02*
X760296Y-213503D01*
X761388Y-212628D01*
X762916Y-212337D01*
X764007Y-212628D01*
X765318Y-213503D01*
G01X830008Y-224003D02*
Y-206503D01*
X834374D01*
X836121Y-207378D01*
X837431Y-208545D01*
X838523Y-210294D01*
X839396Y-212337D01*
X839614Y-215253D01*
X839396Y-218170D01*
X838523Y-220212D01*
X837431Y-221962D01*
X836121Y-223128D01*
X834374Y-224003D01*
X830008D01*
G01X849036Y-216128D02*
X856023D01*
X855368Y-214086D01*
X854276Y-212920D01*
X852748Y-212337D01*
X851219Y-212628D01*
X849909Y-213503D01*
X849036Y-215545D01*
X848599Y-217295D01*
Y-219045D01*
X849036Y-220795D01*
X850128Y-222545D01*
X851438Y-223711D01*
X852966Y-224003D01*
X854494Y-223420D01*
X856023Y-221670D01*
G01X866536Y-221962D02*
X867628Y-223128D01*
X869156Y-224003D01*
X870466D01*
X871776Y-223420D01*
X872649Y-222545D01*
X873086Y-221379D01*
X872868Y-219628D01*
X871994Y-218753D01*
X868064Y-217003D01*
X867191Y-214961D01*
X867628Y-213503D01*
X868501Y-212628D01*
X869811Y-212337D01*
X871121Y-212628D01*
X872431Y-213503D01*
G01X887311Y-212337D02*
Y-224003D01*
G01Y-207670D02*
X886874Y-207378D01*
Y-206795D01*
X887311Y-206503D01*
X887748Y-206795D01*
Y-207378D01*
X887311Y-207670D01*
G01X901754Y-228378D02*
X903283Y-229545D01*
X905029Y-229836D01*
X906557Y-229545D01*
X907868Y-228087D01*
X908741Y-226045D01*
Y-212337D01*
G01Y-214670D02*
X907868Y-213503D01*
X906557Y-212628D01*
X905029Y-212337D01*
X903283Y-212920D01*
X902191Y-214086D01*
X901317Y-216128D01*
X900881Y-218170D01*
X901099Y-219920D01*
X901973Y-221962D01*
X903283Y-223420D01*
X905029Y-224003D01*
X906339Y-223711D01*
X907868Y-222545D01*
X908741Y-221379D01*
G01X918599Y-224003D02*
Y-212337D01*
G01Y-215253D02*
X919473Y-213795D01*
X920783Y-212628D01*
X922529Y-212337D01*
X924057Y-212628D01*
X925368Y-213795D01*
X926023Y-215836D01*
Y-224003D01*
G01X936536Y-216128D02*
X943523D01*
X942868Y-214086D01*
X941776Y-212920D01*
X940248Y-212337D01*
X938719Y-212628D01*
X937409Y-213503D01*
X936536Y-215545D01*
X936099Y-217295D01*
Y-219045D01*
X936536Y-220795D01*
X937628Y-222545D01*
X938938Y-223711D01*
X940466Y-224003D01*
X941994Y-223420D01*
X943523Y-221670D01*
G01X954254Y-224003D02*
Y-212337D01*
G01Y-214670D02*
X955346Y-213503D01*
X956438Y-212628D01*
X957966Y-212337D01*
X959057Y-212628D01*
X960368Y-213503D01*
G01X874194Y-265503D02*
X875286Y-267253D01*
X876596Y-268420D01*
X878124Y-269003D01*
X879871Y-268420D01*
X881181Y-267253D01*
X882491Y-265503D01*
X882928Y-263170D01*
Y-251503D01*
G01X896061Y-269003D02*
X894314Y-268711D01*
X892786Y-267545D01*
X891476Y-265795D01*
X890602Y-263753D01*
X890166Y-261420D01*
Y-259086D01*
X890602Y-256753D01*
X891476Y-254711D01*
X892786Y-252962D01*
X894314Y-251795D01*
X896061Y-251503D01*
X897807Y-251795D01*
X899336Y-252962D01*
X900646Y-254711D01*
X901520Y-256753D01*
X901956Y-259086D01*
Y-261420D01*
X901520Y-263753D01*
X900646Y-265795D01*
X899336Y-267545D01*
X897807Y-268711D01*
X896061Y-269003D01*
G01X913561D02*
Y-261128D01*
X909194Y-251503D01*
G01X917928D02*
X913561Y-261128D01*
G01X1001011Y-269003D02*
Y-251503D01*
X998391Y-255003D01*
G01Y-269003D02*
X1003631D01*
G01X1014363Y-254420D02*
X1015673Y-252670D01*
X1017201Y-251795D01*
X1018948Y-251503D01*
X1021131Y-252086D01*
X1022659Y-253545D01*
X1023096Y-255294D01*
X1022878Y-257045D01*
X1022004Y-258503D01*
X1017638Y-261420D01*
X1015673Y-263461D01*
X1014363Y-266379D01*
X1013926Y-269003D01*
X1023096D01*
G01X1032081Y-269586D02*
X1039941Y-251503D01*
G01X1048708Y-265503D02*
X1050017Y-267545D01*
X1051764Y-268711D01*
X1053729Y-269003D01*
X1055476Y-268711D01*
X1057223Y-267253D01*
X1058314Y-265503D01*
X1058533Y-263753D01*
X1058096Y-261712D01*
X1056568Y-260253D01*
X1055039Y-259670D01*
X1053074D01*
G01X1055039D02*
X1056349Y-258795D01*
X1057441Y-257337D01*
X1057878Y-255587D01*
X1057441Y-253836D01*
X1056349Y-252378D01*
X1054384Y-251503D01*
X1052419Y-251795D01*
X1050454Y-252962D01*
G01X1071011Y-251503D02*
X1069264Y-252086D01*
X1067954Y-253545D01*
X1067081Y-255294D01*
X1066426Y-257628D01*
X1066208Y-260253D01*
X1066426Y-262878D01*
X1067081Y-265212D01*
X1067954Y-266962D01*
X1069264Y-268420D01*
X1071011Y-269003D01*
X1072757Y-268420D01*
X1074068Y-266962D01*
X1074941Y-265212D01*
X1075596Y-262878D01*
X1075814Y-260253D01*
X1075596Y-257628D01*
X1074941Y-255294D01*
X1074068Y-253545D01*
X1072757Y-252086D01*
X1071011Y-251503D01*
G01X1084581Y-269586D02*
X1092441Y-251503D01*
G01X1101863Y-254420D02*
X1103173Y-252670D01*
X1104701Y-251795D01*
X1106448Y-251503D01*
X1108631Y-252086D01*
X1110159Y-253545D01*
X1110596Y-255294D01*
X1110378Y-257045D01*
X1109504Y-258503D01*
X1105138Y-261420D01*
X1103173Y-263461D01*
X1101863Y-266379D01*
X1101426Y-269003D01*
X1110596D01*
G01X1123511Y-251503D02*
X1121764Y-252086D01*
X1120454Y-253545D01*
X1119581Y-255294D01*
X1118926Y-257628D01*
X1118708Y-260253D01*
X1118926Y-262878D01*
X1119581Y-265212D01*
X1120454Y-266962D01*
X1121764Y-268420D01*
X1123511Y-269003D01*
X1125257Y-268420D01*
X1126568Y-266962D01*
X1127441Y-265212D01*
X1128096Y-262878D01*
X1128314Y-260253D01*
X1128096Y-257628D01*
X1127441Y-255294D01*
X1126568Y-253545D01*
X1125257Y-252086D01*
X1123511Y-251503D01*
G01X1141011Y-269003D02*
Y-251503D01*
X1138391Y-255003D01*
G01Y-269003D02*
X1143631D01*
G01X1154363Y-261712D02*
X1155891Y-259670D01*
X1157201Y-258503D01*
X1158948Y-257920D01*
X1160476Y-258503D01*
X1161568Y-259670D01*
X1162441Y-261420D01*
X1162659Y-263461D01*
X1162441Y-265212D01*
X1161568Y-266962D01*
X1160257Y-268420D01*
X1158729Y-269003D01*
X1156983Y-268420D01*
X1155454Y-266670D01*
X1154581Y-264045D01*
X1154363Y-261128D01*
X1154799Y-257337D01*
X1155454Y-255294D01*
X1156546Y-253253D01*
X1158074Y-251795D01*
X1159603Y-251503D01*
X1161131Y-252086D01*
X1162223Y-253545D01*
G01X1048708Y-224003D02*
Y-206503D01*
X1053074D01*
X1054821Y-207378D01*
X1056131Y-208545D01*
X1057223Y-210294D01*
X1058096Y-212337D01*
X1058314Y-215253D01*
X1058096Y-218170D01*
X1057223Y-220212D01*
X1056131Y-221962D01*
X1054821Y-223128D01*
X1053074Y-224003D01*
X1048708D01*
G01X1074941D02*
Y-212337D01*
G01Y-214378D02*
X1074068Y-213212D01*
X1072757Y-212628D01*
X1071229Y-212337D01*
X1069701Y-212920D01*
X1068391Y-214086D01*
X1067517Y-215836D01*
X1067081Y-218170D01*
X1067517Y-220503D01*
X1068391Y-222253D01*
X1069701Y-223420D01*
X1071229Y-224003D01*
X1072757Y-223711D01*
X1074068Y-222837D01*
X1074941Y-221670D01*
G01X1088511Y-206503D02*
Y-224003D01*
G01X1085454Y-212337D02*
X1091568D01*
G01X1102736Y-216128D02*
X1109723D01*
X1109068Y-214086D01*
X1107976Y-212920D01*
X1106448Y-212337D01*
X1104919Y-212628D01*
X1103609Y-213503D01*
X1102736Y-215545D01*
X1102299Y-217295D01*
Y-219045D01*
X1102736Y-220795D01*
X1103828Y-222545D01*
X1105138Y-223711D01*
X1106666Y-224003D01*
X1108194Y-223420D01*
X1109723Y-221670D01*
M02*
